(kicad_pcb
	(version 20260206)
	(generator "pcbnew")
	(generator_version "10.0")
	(general
		(thickness 1.6)
		(legacy_teardrops no)
	)
	(paper "A4")
	(title_block
		(title "Bryce Canyon_R.DPB_16317-1_OCP.brd")
		(comment 1 "Bryce Canyon / footprints 802-807 of 2099")
	)
	(layers
		(0 "F.Cu" signal "TOP")
		(4 "In1.Cu" signal "L2GND")
		(6 "In2.Cu" signal "L3")
		(8 "In3.Cu" signal "L4VCC")
		(10 "In4.Cu" signal "L5VCC")
		(12 "In5.Cu" signal "L6")
		(14 "In6.Cu" signal "L7GND")
		(2 "B.Cu" signal "BOTTOM")
		(9 "F.Adhes" user "F.Adhesive")
		(11 "B.Adhes" user "B.Adhesive")
		(13 "F.Paste" user "Package Geometry/Pastemask Top")
		(15 "B.Paste" user "Package Geometry/Pastemask Bottom")
		(5 "F.SilkS" user "Ref Des/Silkscreen Top")
		(7 "B.SilkS" user "Ref Des/Silkscreen Bottom")
		(1 "F.Mask" user "Board Geometry/Soldermask Top")
		(3 "B.Mask" user "Board Geometry/Soldermask Bottom")
		(17 "Dwgs.User" user "User.Drawings")
		(19 "Cmts.User" user "User.Comments")
		(21 "Eco1.User" user "User.Eco1")
		(23 "Eco2.User" user "User.Eco2")
		(25 "Edge.Cuts" user "Board Geometry/Outline")
		(27 "Margin" user)
		(31 "F.CrtYd" user "Package Geometry/Place Bound Top")
		(29 "B.CrtYd" user "Package Geometry/Place Bound Bottom")
		(35 "F.Fab" user "Ref Des/Assembly Top")
		(33 "B.Fab" user "Ref Des/Assembly Bottom")
	)
	(footprint ""
		(layer "F.Cu")
		(at 353.314 -261.6454)
		(property "Reference" "C123"
			(at 0 0 0)
			(layer "F.SilkS")
			(hide yes)
			(effects
				(font
					(size 1.27 1.27)
				)
			)
		)
		(property "Value" "SCD01U50V2KX-1GP"
			(at 1.1811 -2.7051 0)
			(unlocked yes)
			(layer "F.Fab")
			(hide yes)
			(effects
				(font
					(size 1.016 1.016)
					(thickness 0.1524)
				)
			)
		)
		(property "Device Type" "C402H22"
			(at 1.1811 -4.2291 0)
			(unlocked yes)
			(layer "F.Fab")
			(hide yes)
			(effects
				(font
					(size 1.016 1.016)
					(thickness 0.1524)
				)
			)
		)
		(duplicate_pad_numbers_are_jumpers no)
		(fp_rect
			(start -0.4318 0.9525)
			(end 0.4318 -0.9525)
			(stroke
				(width 0)
				(type default)
			)
			(fill no)
			(layer "F.CrtYd")
		)
		(fp_rect
			(start -0.4318 0.9525)
			(end 0.4318 -0.9525)
			(stroke
				(width 0)
				(type default)
			)
			(fill no)
			(layer "F.Fab")
		)
		(pad "1" smd custom
			(at 0 -0.4445)
			(size 0.1524 0.1524)
			(layers "F.Cu" "F.Mask" "F.Paste")
			(net "HDD_PRSNT_7")
			(options
				(clearance outline)
				(anchor circle)
			)
			(primitives
				(gr_poly
					(pts
						(arc
							(start 0.3048 -0.2032)
							(mid 0.275042 -0.275042)
							(end 0.2032 -0.3048)
						)
						(arc
							(start -0.2032 -0.3048)
							(mid -0.275042 -0.275042)
							(end -0.3048 -0.2032)
						)
						(arc
							(start -0.3048 0.2032)
							(mid -0.275042 0.275042)
							(end -0.2032 0.3048)
						)
						(arc
							(start 0.2032 0.3048)
							(mid 0.275042 0.275042)
							(end 0.3048 0.2032)
						)
					)
					(width 0)
					(fill yes)
				)
			)
		)
		(pad "2" smd custom
			(at 0 0.4445)
			(size 0.1524 0.1524)
			(layers "F.Cu" "F.Mask" "F.Paste")
			(net "GND")
			(options
				(clearance outline)
				(anchor circle)
			)
			(primitives
				(gr_poly
					(pts
						(arc
							(start 0.3048 -0.2032)
							(mid 0.275042 -0.275042)
							(end 0.2032 -0.3048)
						)
						(arc
							(start -0.2032 -0.3048)
							(mid -0.275042 -0.275042)
							(end -0.3048 -0.2032)
						)
						(arc
							(start -0.3048 0.2032)
							(mid -0.275042 0.275042)
							(end -0.2032 0.3048)
						)
						(arc
							(start 0.2032 0.3048)
							(mid 0.275042 0.275042)
							(end 0.3048 0.2032)
						)
					)
					(width 0)
					(fill yes)
				)
			)
		)
	)
	(footprint ""
		(layer "F.Cu")
		(at 331.978 -23.368 180)
		(property "Reference" "Q154"
			(at 0 0 180)
			(layer "F.SilkS")
			(hide yes)
			(effects
				(font
					(size 1.27 1.27)
				)
			)
		)
		(property "Value" "AO4406AL-GP"
			(at -3.707384 -1.5367 180)
			(unlocked yes)
			(layer "F.Fab")
			(hide yes)
			(effects
				(font
					(size 1.016 1.016)
					(thickness 0.1524)
				)
			)
		)
		(property "Device Type" "SOIC8H69"
			(at -3.707384 -3.0607 180)
			(unlocked yes)
			(layer "F.Fab")
			(hide yes)
			(effects
				(font
					(size 1.016 1.016)
					(thickness 0.1524)
				)
			)
		)
		(duplicate_pad_numbers_are_jumpers no)
		(fp_line
			(start 2.1336 1.4224)
			(end 2.1336 -1.4224)
			(stroke
				(width 0.1524)
				(type default)
			)
			(layer "F.SilkS")
		)
		(fp_line
			(start 2.1336 -1.4224)
			(end -2.7432 -1.4224)
			(stroke
				(width 0.1524)
				(type default)
			)
			(layer "F.SilkS")
		)
		(fp_line
			(start -2.1844 -0.0508)
			(end -2.7178 0.508)
			(stroke
				(width 0.1524)
				(type default)
			)
			(layer "F.SilkS")
		)
		(fp_line
			(start -2.6289 3.4417)
			(end -2.6289 1.4732)
			(stroke
				(width 0.381)
				(type default)
			)
			(layer "F.SilkS")
		)
		(fp_line
			(start -2.7178 -0.508)
			(end -2.1844 -0.0508)
			(stroke
				(width 0.1524)
				(type default)
			)
			(layer "F.SilkS")
		)
		(fp_line
			(start -2.7432 1.4224)
			(end 2.1336 1.4224)
			(stroke
				(width 0.1524)
				(type default)
			)
			(layer "F.SilkS")
		)
		(fp_line
			(start -2.7432 1.4224)
			(end -2.6416 1.4224)
			(stroke
				(width 0.1524)
				(type default)
			)
			(layer "F.SilkS")
		)
		(fp_line
			(start -2.7432 -1.4224)
			(end -2.7432 1.4224)
			(stroke
				(width 0.1524)
				(type default)
			)
			(layer "F.SilkS")
		)
		(fp_poly
			(pts
				(xy -2.2098 -1.4224) (xy -2.2098 1.4224) (xy 2.2098 1.4224) (xy 2.2098 -1.4224)
			)
			(stroke
				(width 0)
				(type default)
			)
			(fill yes)
			(layer "F.SilkS")
		)
		(fp_rect
			(start -2.450084 2.999994)
			(end 2.450084 -2.999994)
			(stroke
				(width 0)
				(type default)
			)
			(fill no)
			(layer "F.CrtYd")
		)
		(fp_poly
			(pts
				(xy -2.8194 3.6322) (xy -2.8194 -3.6322) (xy 2.8194 -3.6322) (xy 2.8194 1.18364) (xy 2.450084 1.18364)
				(xy 2.450084 -2.999994) (xy -2.450084 -2.999994) (xy -2.450084 2.999994) (xy 2.450084 2.999994)
				(xy 2.450084 1.18618) (xy 2.8194 1.18618) (xy 2.8194 3.6322)
			)
			(stroke
				(width 0)
				(type default)
			)
			(fill no)
			(layer "F.CrtYd")
		)
		(fp_rect
			(start -2.8194 3.6322)
			(end 2.8194 -3.6322)
			(stroke
				(width 0)
				(type default)
			)
			(fill no)
			(layer "F.Fab")
		)
		(pad "1" smd rect
			(at -1.905 2.54 180)
			(size 0.635 1.651)
			(layers "F.Cu" "F.Mask" "F.Paste")
			(net "P5V_HDD30")
		)
		(pad "2" smd rect
			(at -0.635 2.54 180)
			(size 0.635 1.651)
			(layers "F.Cu" "F.Mask" "F.Paste")
			(net "P5V_HDD30")
		)
		(pad "3" smd rect
			(at 0.635 2.54 180)
			(size 0.635 1.651)
			(layers "F.Cu" "F.Mask" "F.Paste")
			(net "P5V_HDD30")
		)
		(pad "4" smd rect
			(at 1.905 2.54 180)
			(size 0.635 1.651)
			(layers "F.Cu" "F.Mask" "F.Paste")
			(net "SW_HDD_P30")
		)
		(pad "5" smd rect
			(at 1.905 -2.54 180)
			(size 0.635 1.651)
			(layers "F.Cu" "F.Mask" "F.Paste")
			(net "P5V_B_4")
		)
		(pad "6" smd rect
			(at 0.635 -2.54 180)
			(size 0.635 1.651)
			(layers "F.Cu" "F.Mask" "F.Paste")
			(net "P5V_B_4")
		)
		(pad "7" smd rect
			(at -0.635 -2.54 180)
			(size 0.635 1.651)
			(layers "F.Cu" "F.Mask" "F.Paste")
			(net "P5V_B_4")
		)
		(pad "8" smd rect
			(at -1.905 -2.54 180)
			(size 0.635 1.651)
			(layers "F.Cu" "F.Mask" "F.Paste")
			(net "P5V_B_4")
		)
	)
	(footprint ""
		(layer "F.Cu")
		(at 425.863004 -364.998 180)
		(property "Reference" "R958"
			(at 0 0 180)
			(layer "F.SilkS")
			(hide yes)
			(effects
				(font
					(size 1.27 1.27)
				)
			)
		)
		(property "Value" "4K7R2F-GP"
			(at 0.064008 -3.993896 180)
			(unlocked yes)
			(layer "F.Fab")
			(hide yes)
			(effects
				(font
					(size 1.016 1.016)
					(thickness 0.1524)
				)
			)
		)
		(property "Device Type" "R402H16"
			(at 0.064008 -5.517896 180)
			(unlocked yes)
			(layer "F.Fab")
			(hide yes)
			(effects
				(font
					(size 1.016 1.016)
					(thickness 0.1524)
				)
			)
		)
		(duplicate_pad_numbers_are_jumpers no)
		(fp_line
			(start 0.508 -0.9398)
			(end -0.508 -0.9398)
			(stroke
				(width 0.1524)
				(type default)
			)
			(layer "F.SilkS")
		)
		(fp_line
			(start -0.508 -0.9398)
			(end -0.508 0.9398)
			(stroke
				(width 0.1524)
				(type default)
			)
			(layer "F.SilkS")
		)
		(fp_rect
			(start -0.508 0.9398)
			(end 0.508 -0.9398)
			(stroke
				(width 0)
				(type default)
			)
			(fill no)
			(layer "F.CrtYd")
		)
		(fp_rect
			(start -0.508 0.9398)
			(end 0.508 -0.9398)
			(stroke
				(width 0)
				(type default)
			)
			(fill no)
			(layer "F.Fab")
		)
		(pad "1" smd custom
			(at 0 -0.4445 180)
			(size 0.1397 0.1397)
			(layers "F.Cu" "F.Mask" "F.Paste")
			(net "P12V_IN")
			(options
				(clearance outline)
				(anchor circle)
			)
			(primitives
				(gr_poly
					(pts
						(arc
							(start -0.1778 -0.2794)
							(mid -0.249642 -0.249642)
							(end -0.2794 -0.1778)
						)
						(arc
							(start -0.2794 0.1778)
							(mid -0.249642 0.249642)
							(end -0.1778 0.2794)
						)
						(arc
							(start 0.1778 0.2794)
							(mid 0.249642 0.249642)
							(end 0.2794 0.1778)
						)
						(arc
							(start 0.2794 -0.1778)
							(mid 0.249642 -0.249642)
							(end 0.1778 -0.2794)
						)
					)
					(width 0)
					(fill yes)
				)
			)
		)
		(pad "2" smd custom
			(at 0 0.4445 180)
			(size 0.1397 0.1397)
			(layers "F.Cu" "F.Mask" "F.Paste")
			(net "FAN_3_TACH1")
			(options
				(clearance outline)
				(anchor circle)
			)
			(primitives
				(gr_poly
					(pts
						(arc
							(start -0.1778 -0.2794)
							(mid -0.249642 -0.249642)
							(end -0.2794 -0.1778)
						)
						(arc
							(start -0.2794 0.1778)
							(mid -0.249642 0.249642)
							(end -0.1778 0.2794)
						)
						(arc
							(start 0.1778 0.2794)
							(mid 0.249642 0.249642)
							(end 0.2794 0.1778)
						)
						(arc
							(start 0.2794 -0.1778)
							(mid 0.249642 -0.249642)
							(end 0.1778 -0.2794)
						)
					)
					(width 0)
					(fill yes)
				)
			)
		)
	)
	(footprint ""
		(layer "F.Cu")
		(at 426.085 -160.02 180)
		(property "Reference" "C307"
			(at 0 0 180)
			(layer "F.SilkS")
			(hide yes)
			(effects
				(font
					(size 1.27 1.27)
				)
			)
		)
		(property "Value" "SC4D7U25V5KX-1-GP"
			(at -0.0762 -6.1214 180)
			(unlocked yes)
			(layer "F.Fab")
			(hide yes)
			(effects
				(font
					(size 1.016 1.016)
					(thickness 0.1524)
				)
			)
		)
		(property "Device Type" "C805H58"
			(at -0.0762 -8.1534 180)
			(unlocked yes)
			(layer "F.Fab")
			(hide yes)
			(effects
				(font
					(size 1.016 1.016)
					(thickness 0.1524)
				)
			)
		)
		(duplicate_pad_numbers_are_jumpers no)
		(fp_line
			(start 0.635 0)
			(end -0.635 0)
			(stroke
				(width 0.508)
				(type default)
			)
			(layer "F.SilkS")
		)
		(fp_rect
			(start -0.9652 1.778)
			(end 0.9652 -1.778)
			(stroke
				(width 0)
				(type default)
			)
			(fill no)
			(layer "F.CrtYd")
		)
		(fp_poly
			(pts
				(xy -0.9652 -1.778) (xy 0.9652 -1.778) (xy 0.9652 1.778) (xy -0.9652 1.778)
			)
			(stroke
				(width 0)
				(type default)
			)
			(fill no)
			(layer "F.Fab")
		)
		(pad "1" smd rect
			(at 0 -0.9652 180)
			(size 1.397 1.143)
			(layers "F.Cu" "F.Mask" "F.Paste")
			(net "P12V_HDD21")
		)
		(pad "2" smd rect
			(at 0 0.9652 180)
			(size 1.397 1.143)
			(layers "F.Cu" "F.Mask" "F.Paste")
			(net "GND")
		)
	)
	(footprint ""
		(layer "F.Cu")
		(at 45.974 -24.384)
		(property "Reference" "Q126"
			(at 0 0 0)
			(layer "F.SilkS")
			(hide yes)
			(effects
				(font
					(size 1.27 1.27)
				)
			)
		)
		(property "Value" "AO4407AL-GP"
			(at -3.707384 -1.5367 0)
			(unlocked yes)
			(layer "F.Fab")
			(hide yes)
			(effects
				(font
					(size 1.016 1.016)
					(thickness 0.1524)
				)
			)
		)
		(property "Device Type" "SOIC8H69"
			(at -3.707384 -3.0607 0)
			(unlocked yes)
			(layer "F.Fab")
			(hide yes)
			(effects
				(font
					(size 1.016 1.016)
					(thickness 0.1524)
				)
			)
		)
		(duplicate_pad_numbers_are_jumpers no)
		(fp_line
			(start -2.7432 -1.4224)
			(end -2.7432 1.4224)
			(stroke
				(width 0.1524)
				(type default)
			)
			(layer "F.SilkS")
		)
		(fp_line
			(start -2.7432 1.4224)
			(end -2.6416 1.4224)
			(stroke
				(width 0.1524)
				(type default)
			)
			(layer "F.SilkS")
		)
		(fp_line
			(start -2.7432 1.4224)
			(end 2.1336 1.4224)
			(stroke
				(width 0.1524)
				(type default)
			)
			(layer "F.SilkS")
		)
		(fp_line
			(start -2.7178 -0.508)
			(end -2.1844 -0.0508)
			(stroke
				(width 0.1524)
				(type default)
			)
			(layer "F.SilkS")
		)
		(fp_line
			(start -2.6289 3.4417)
			(end -2.6289 1.4732)
			(stroke
				(width 0.381)
				(type default)
			)
			(layer "F.SilkS")
		)
		(fp_line
			(start -2.1844 -0.0508)
			(end -2.7178 0.508)
			(stroke
				(width 0.1524)
				(type default)
			)
			(layer "F.SilkS")
		)
		(fp_line
			(start 2.1336 -1.4224)
			(end -2.7432 -1.4224)
			(stroke
				(width 0.1524)
				(type default)
			)
			(layer "F.SilkS")
		)
		(fp_line
			(start 2.1336 1.4224)
			(end 2.1336 -1.4224)
			(stroke
				(width 0.1524)
				(type default)
			)
			(layer "F.SilkS")
		)
		(fp_poly
			(pts
				(xy -2.2098 -1.4224) (xy -2.2098 1.4224) (xy 2.2098 1.4224) (xy 2.2098 -1.4224)
			)
			(stroke
				(width 0)
				(type default)
			)
			(fill yes)
			(layer "F.SilkS")
		)
		(fp_rect
			(start -2.450084 2.999994)
			(end 2.450084 -2.999994)
			(stroke
				(width 0)
				(type default)
			)
			(fill no)
			(layer "F.CrtYd")
		)
		(fp_poly
			(pts
				(xy -2.8194 3.6322) (xy -2.8194 -3.6322) (xy 2.8194 -3.6322) (xy 2.8194 1.18364) (xy 2.450084 1.18364)
				(xy 2.450084 -2.999994) (xy -2.450084 -2.999994) (xy -2.450084 2.999994) (xy 2.450084 2.999994)
				(xy 2.450084 1.18618) (xy 2.8194 1.18618) (xy 2.8194 3.6322)
			)
			(stroke
				(width 0)
				(type default)
			)
			(fill no)
			(layer "F.CrtYd")
		)
		(fp_rect
			(start -2.8194 3.6322)
			(end 2.8194 -3.6322)
			(stroke
				(width 0)
				(type default)
			)
			(fill no)
			(layer "F.Fab")
		)
		(pad "1" smd rect
			(at -1.905 2.54)
			(size 0.635 1.651)
			(layers "F.Cu" "F.Mask" "F.Paste")
			(net "P12V_B")
		)
		(pad "2" smd rect
			(at -0.635 2.54)
			(size 0.635 1.651)
			(layers "F.Cu" "F.Mask" "F.Paste")
			(net "P12V_B")
		)
		(pad "3" smd rect
			(at 0.635 2.54)
			(size 0.635 1.651)
			(layers "F.Cu" "F.Mask" "F.Paste")
			(net "P12V_B")
		)
		(pad "4" smd rect
			(at 1.905 2.54)
			(size 0.635 1.651)
			(layers "F.Cu" "F.Mask" "F.Paste")
			(net "SW_HDD_N25")
		)
		(pad "5" smd rect
			(at 1.905 -2.54)
			(size 0.635 1.651)
			(layers "F.Cu" "F.Mask" "F.Paste")
			(net "P12V_HDD25")
		)
		(pad "6" smd rect
			(at 0.635 -2.54)
			(size 0.635 1.651)
			(layers "F.Cu" "F.Mask" "F.Paste")
			(net "P12V_HDD25")
		)
		(pad "7" smd rect
			(at -0.635 -2.54)
			(size 0.635 1.651)
			(layers "F.Cu" "F.Mask" "F.Paste")
			(net "P12V_HDD25")
		)
		(pad "8" smd rect
			(at -1.905 -2.54)
			(size 0.635 1.651)
			(layers "F.Cu" "F.Mask" "F.Paste")
			(net "P12V_HDD25")
		)
	)
	(footprint ""
		(layer "F.Cu")
		(at 395.478 -266.827 180)
		(property "Reference" "C135"
			(at 0 0 180)
			(layer "F.SilkS")
			(hide yes)
			(effects
				(font
					(size 1.27 1.27)
				)
			)
		)
		(property "Value" "SC10U16V6KX-2GP"
			(at -0.0762 -5.1308 180)
			(unlocked yes)
			(layer "F.Fab")
			(hide yes)
			(effects
				(font
					(size 1.016 1.016)
					(thickness 0.1524)
				)
			)
		)
		(property "Device Type" "C1206H71"
			(at -0.127 -6.6548 180)
			(unlocked yes)
			(layer "F.Fab")
			(hide yes)
			(effects
				(font
					(size 1.016 1.016)
					(thickness 0.1524)
				)
			)
		)
		(duplicate_pad_numbers_are_jumpers no)
		(fp_line
			(start 1.016 2.2352)
			(end -1.016 2.2352)
			(stroke
				(width 0.1524)
				(type default)
			)
			(layer "F.SilkS")
		)
		(fp_line
			(start 1.016 0.8382)
			(end 1.016 2.2352)
			(stroke
				(width 0.1524)
				(type default)
			)
			(layer "F.SilkS")
		)
		(fp_line
			(start 1.016 -2.2352)
			(end 1.016 -0.8382)
			(stroke
				(width 0.1524)
				(type default)
			)
			(layer "F.SilkS")
		)
		(fp_line
			(start -1.016 2.2352)
			(end -1.016 0.8382)
			(stroke
				(width 0.1524)
				(type default)
			)
			(layer "F.SilkS")
		)
		(fp_line
			(start -1.016 -0.8382)
			(end -1.016 -2.2352)
			(stroke
				(width 0.1524)
				(type default)
			)
			(layer "F.SilkS")
		)
		(fp_line
			(start -1.016 -2.2352)
			(end 1.016 -2.2352)
			(stroke
				(width 0.1524)
				(type default)
			)
			(layer "F.SilkS")
		)
		(fp_rect
			(start -1.0922 2.3114)
			(end 1.0922 -2.3114)
			(stroke
				(width 0)
				(type default)
			)
			(fill no)
			(layer "F.CrtYd")
		)
		(fp_poly
			(pts
				(xy 1.0922 -2.3114) (xy 1.0922 2.3114) (xy -1.0922 2.3114) (xy -1.0922 -2.3114)
			)
			(stroke
				(width 0)
				(type default)
			)
			(fill no)
			(layer "F.Fab")
		)
		(pad "1" smd rect
			(at 0 -1.397 180)
			(size 1.651 1.27)
			(layers "F.Cu" "F.Mask" "F.Paste")
			(net "P5V_HDD8")
		)
		(pad "2" smd rect
			(at 0 1.397 180)
			(size 1.651 1.27)
			(layers "F.Cu" "F.Mask" "F.Paste")
			(net "GND")
		)
	)
)
